FILE_TYPE = CONNECTIVITY;
{Allegro Design Entry HDL 16.6-p007 (v16-6-112F) 10/10/2012}
"PAGE_NUMBER" = 29;
0"NC";
1"DMI_CPU0_PCH_TX_DP<3:0>";
2"DMI_CPU0_PCH_TX_DN<3:0>";
3"DMI_CPU0_PCH_RX_C_DP<3:0>";
4"DMI_CPU0_PCH_RX_C_DN<3:0>";
5"PVCCMCP_CPU0\g";
6"TP_CPU0_RSVD_186";
7"CLK_156M_OSC_CPU0_HFI_DN";
8"SMB_HFI1_CPU0_LVC2_SCL";
9"SMB_HFI1_CPU0_LVC2_SDA";
10"RST_CD_CPU0_POR_N";
11"JTAG_MCP_CPU0_TDO";
12"FM_MODPRST_HFI1_CPU0_LVT2_N";
13"LED_HFI1_CPU0_N";
14"CLK_156M_OSC_CPU0_HFI_DP";
15"TP_CPU0_RSVD_182";
16"TP_CPU0_RSVD_183";
17"TP_CPU0_RSVD_174";
18"TP_CPU0_RSVD_175";
19"TP_CPU0_RSVD_176";
20"TP_CPU0_RSVD_177";
21"TP_CPU0_RSVD_178";
22"TP_CPU0_RSVD_179";
23"TP_CPU0_RSVD_180";
24"TP_CPU0_RSVD_181";
25"SMB_HFI0_CPU0_LVC2_SCL";
26"SMB_HFI0_CPU0_LVC2_SDA";
27"IRQ_HFI0_CPU0_LVT2_N";
28"LED_HFI0_CPU0_N";
29"FM_MODPRST_HFI0_CPU0_LVT2_N";
30"RST_HFI0_CPU0_LVT2_N";
31"IRQ_HFI1_CPU0_LVT2_N";
32"RST_HFI1_CPU0_LVT2_N";
33"CLK_100M_CPU0_PE_REFCLK_DN";
34"CLK_100M_CPU0_PE_REFCLK_DP";
35"JTAG_MCP_TCK";
36"JTAG_MCP_CPU0_TDI";
37"JTAG_MCP_TMS";
38"JTAG_MCP_TRST_N";
39"DMI_CPU0_PCH_RX_C_DN<3>";
40"DMI_CPU0_PCH_RX_C_DN<2>";
41"DMI_CPU0_PCH_RX_C_DN<1>";
42"DMI_CPU0_PCH_RX_C_DN<0>";
43"DMI_CPU0_PCH_RX_C_DP<3>";
44"DMI_CPU0_PCH_RX_C_DP<2>";
45"DMI_CPU0_PCH_RX_C_DP<1>";
46"DMI_CPU0_PCH_RX_C_DP<0>";
47"DMI_CPU0_PCH_TX_DN<3>";
48"DMI_CPU0_PCH_TX_DN<2>";
49"DMI_CPU0_PCH_TX_DN<1>";
50"DMI_CPU0_PCH_TX_DN<0>";
51"DMI_CPU0_PCH_TX_DP<3>";
52"DMI_CPU0_PCH_TX_DP<2>";
53"DMI_CPU0_PCH_TX_DP<1>";
54"DMI_CPU0_PCH_TX_DP<0>";
55"TP_CPU0_RSVD_190";
56"TP_CPU0_RSVD_189";
57"TP_CPU0_RSVD_184";
58"TP_CPU0_RSVD_173";
59"TP_CPU0_RSVD_172";
%"TAP"
"1","(-5050,3150)","2","mstr_standard","I10";
;
CDS_LIB"mstr_standard"
BODY_TYPE"PLUMBING"
HDL_TAP"TRUE";
"B \NAC \NWC"4;
"S \NAC"
BN"2"40;
%"TAP"
"1","(-5050,3300)","2","mstr_standard","I11";
;
CDS_LIB"mstr_standard"
BODY_TYPE"PLUMBING"
HDL_TAP"TRUE";
"B \NAC \NWC"3;
"S \NAC"
BN"0"46;
%"TAP"
"1","(-5050,3350)","2","mstr_standard","I12";
;
CDS_LIB"mstr_standard"
BODY_TYPE"PLUMBING"
HDL_TAP"TRUE";
"B \NAC \NWC"3;
"S \NAC"
BN"1"45;
%"TAP"
"1","(-5050,3400)","2","mstr_standard","I13";
;
CDS_LIB"mstr_standard"
BODY_TYPE"PLUMBING"
HDL_TAP"TRUE";
"B \NAC \NWC"3;
"S \NAC"
BN"2"44;
%"TAP"
"1","(-5050,3450)","2","mstr_standard","I14";
;
CDS_LIB"mstr_standard"
BODY_TYPE"PLUMBING"
HDL_TAP"TRUE";
"B \NAC \NWC"3;
"S \NAC"
BN"3"43;
%"TAP"
"1","(-2750,3100)","0","mstr_standard","I16";
;
CDS_LIB"mstr_standard"
BODY_TYPE"PLUMBING"
HDL_TAP"TRUE";
"B \NAC \NWC"2;
"S \NAC"
BN"1"49;
%"TAP"
"1","(-2750,3050)","0","mstr_standard","I17";
;
CDS_LIB"mstr_standard"
BODY_TYPE"PLUMBING"
HDL_TAP"TRUE";
"B \NAC \NWC"2;
"S \NAC"
BN"0"50;
%"TAP"
"1","(-2750,3200)","0","mstr_standard","I18";
;
CDS_LIB"mstr_standard"
BODY_TYPE"PLUMBING"
HDL_TAP"TRUE";
"B \NAC \NWC"2;
"S \NAC"
BN"3"47;
%"TAP"
"1","(-2750,3150)","0","mstr_standard","I19";
;
CDS_LIB"mstr_standard"
BODY_TYPE"PLUMBING"
HDL_TAP"TRUE";
"B \NAC \NWC"2;
"S \NAC"
BN"2"48;
%"TAP"
"1","(-2750,3300)","0","mstr_standard","I20";
;
CDS_LIB"mstr_standard"
BODY_TYPE"PLUMBING"
HDL_TAP"TRUE";
"B \NAC \NWC"1;
"S \NAC"
BN"0"54;
%"TAP"
"1","(-2750,3400)","0","mstr_standard","I21";
;
CDS_LIB"mstr_standard"
BODY_TYPE"PLUMBING"
HDL_TAP"TRUE";
"B \NAC \NWC"1;
"S \NAC"
BN"2"52;
%"TAP"
"1","(-2750,3350)","0","mstr_standard","I22";
;
CDS_LIB"mstr_standard"
BODY_TYPE"PLUMBING"
HDL_TAP"TRUE";
"B \NAC \NWC"1;
"S \NAC"
BN"1"53;
%"TAP"
"1","(-2750,3450)","0","mstr_standard","I23";
;
CDS_LIB"mstr_standard"
BODY_TYPE"PLUMBING"
HDL_TAP"TRUE";
"B \NAC \NWC"1;
"S \NAC"
BN"3"51;
%"VCC_CORE"
"1","(-1075,2275)","0","mstr_symbols","I60";
;
HDL_POWER"PVCCMCP_CPU0"
CDS_LIB"mstr_symbols";
"A"5;
%"SKX_EXT_B"
"9","(-3900,2550)","0","chpset_lib","I61";
;
CDS_SEC"9"
LOCATION"U5D1"
PART_NUMBER"TBD"
MATERIAL"IC"
PACK_TYPE"BGA1"
CDS_LIB"chpset_lib"
SEC_TYPE"BGA1"
SEC"9"
CDS_LOCATION"U5D1"
ROOM"CPU0";
"RSVD<172>"
$PN"BA76"59;
"RSVD<173>"
$PN"BA66"58;
"RSVD<174>"
$PN"BA64"17;
"RSVD<175>"
$PN"BA22"18;
"RSVD<176>"
$PN"BA18"19;
"RSVD<177>"
$PN"BA16"20;
"RSVD<178>"
$PN"BA14"21;
"RSVD<179>"
$PN"AY77"22;
"RSVD<180>"
$PN"AY75"23;
"RSVD<181>"
$PN"AY67"24;
"RSVD<182>"
$PN"AY65"15;
"RSVD<183>"
$PN"AW76"16;
"RSVD<184>"
$PN"AW64"57;
"RSVD<186>"
$PN"AV77"6;
"RSVD<187>"
$PN"AT25"5;
"RSVD<188>"
$PN"AT23"5;
"RSVD<189>"
$PN"AT13"56;
"RSVD<190>"
$PN"AR62"55;
"RSVD<191>"
$PN"AR26"5;
"RSVD<192>"
$PN"AR22"5;
"RSVD<193>"
$PN"AR20"5;
"DMI_TX_DP<0>"
$PN"CH5"54;
"DMI_TX_DP<1>"
$PN"CL4"53;
"DMI_TX_DP<2>"
$PN"CM3"52;
"DMI_TX_DP<3>"
$PN"CR4"51;
"DMI_TX_DN<0>"
$PN"CG4"50;
"DMI_TX_DN<1>"
$PN"CJ4"49;
"DMI_TX_DN<2>"
$PN"CN4"48;
"DMI_TX_DN<3>"
$PN"CP5"47;
"DMI_RX_DP<0>"
$PN"CL10"46;
"DMI_RX_DP<1>"
$PN"CN10"45;
"DMI_RX_DP<2>"
$PN"CP11"44;
"DMI_RX_DP<3>"
$PN"CV11"43;
"DMI_RX_DN<0>"
$PN"CK9"42;
"DMI_RX_DN<1>"
$PN"CM11"41;
"DMI_RX_DN<2>"
$PN"CR12"40;
"DMI_RX_DN<3>"
$PN"CT11"39;
"CD_TRST_N"
$PN"CD23"38;
"CD_TMS"
$PN"CE24"37;
"CD_TDO"
$PN"CC22"11;
"CD_TDI"
$PN"BY21"36;
"CD_TCLK"
$PN"CB23"35;
"CD_POR_N"
$PN"CF25"10;
"CD_PE_REFCLK_DP"
$PN"BW24"34;
"CD_PE_REFCLK_DN"
$PN"BU24"33;
"CD_HFI_REFCLK_DP"
$PN"BG16"14;
"CD_HFI_REFCLK_DN"
$PN"BE16"7;
"CD_HFI1_RESET_N"
$PN"BK23"32;
"CD_HFI1_MODPRST_N"
$PN"BT19"12;
"CD_HFI1_LED_N"
$PN"BM23"13;
"CD_HFI1_INT_N"
$PN"BM21"31;
"CD_HFI1_I2CDAT"
$PN"BH23"9;
"CD_HFI1_I2CCLK"
$PN"BJ22"8;
"CD_HFI0_RESET_N"
$PN"BN24"30;
"CD_HFI0_MODPRST_N"
$PN"BR20"29;
"CD_HFI0_LED_N"
$PN"BK21"28;
"CD_HFI0_INT_N"
$PN"BP19"27;
"CD_HFI0_I2CDAT"
$PN"BP23"26;
"CD_HFI0_I2CCLK"
$PN"BN22"25;
%"TAP"
"1","(-5050,3050)","2","mstr_standard","I7";
;
CDS_LIB"mstr_standard"
BODY_TYPE"PLUMBING"
HDL_TAP"TRUE";
"B \NAC \NWC"4;
"S \NAC"
BN"0"42;
%"TAP"
"1","(-5050,3100)","2","mstr_standard","I8";
;
CDS_LIB"mstr_standard"
BODY_TYPE"PLUMBING"
HDL_TAP"TRUE";
"B \NAC \NWC"4;
"S \NAC"
BN"1"41;
%"TAP"
"1","(-5050,3200)","2","mstr_standard","I9";
;
CDS_LIB"mstr_standard"
BODY_TYPE"PLUMBING"
HDL_TAP"TRUE";
"B \NAC \NWC"4;
"S \NAC"
BN"3"39;
END.
